(kicad_pcb
	(version 20260206)
	(generator "pcbnew")
	(generator_version "10.0")
	(general
		(thickness 1.6)
		(legacy_teardrops no)
	)
	(paper "A4")
	(title_block
		(title "Wiwynn_Tioga_Pass_MB.brd")
		(comment 1 "Tioga Pass / footprint 1251 of 4770 (J8A1), pads 76-77 of 77")
	)
	(layers
		(0 "F.Cu" signal "TOP")
		(4 "In1.Cu" signal "L2GND")
		(6 "In2.Cu" signal "L3")
		(8 "In3.Cu" signal "L4GND")
		(10 "In4.Cu" signal "L5")
		(12 "In5.Cu" signal "L6GND")
		(14 "In6.Cu" signal "L7VCC")
		(16 "In7.Cu" signal "L8VCC")
		(18 "In8.Cu" signal "L9GND")
		(20 "In9.Cu" signal "L10")
		(22 "In10.Cu" signal "L11GND")
		(24 "In11.Cu" signal "L12")
		(26 "In12.Cu" signal "L13GND")
		(2 "B.Cu" signal "BOTTOM")
		(9 "F.Adhes" user "F.Adhesive")
		(11 "B.Adhes" user "B.Adhesive")
		(13 "F.Paste" user "Package Geometry/Pastemask Top")
		(15 "B.Paste" user "Package Geometry/Pastemask Bottom")
		(5 "F.SilkS" user "Ref Des/Silkscreen Top")
		(7 "B.SilkS" user "Ref Des/Silkscreen Bottom")
		(1 "F.Mask" user "Board Geometry/Soldermask Top")
		(3 "B.Mask" user "Board Geometry/Soldermask Bottom")
		(17 "Dwgs.User" user "User.Drawings")
		(19 "Cmts.User" user "User.Comments")
		(21 "Eco1.User" user "User.Eco1")
		(23 "Eco2.User" user "User.Eco2")
		(25 "Edge.Cuts" user "Board Geometry/Outline")
		(27 "Margin" user)
		(31 "F.CrtYd" user "Package Geometry/Place Bound Top")
		(29 "B.CrtYd" user "Package Geometry/Place Bound Bottom")
		(35 "F.Fab" user "Ref Des/Assembly Top")
		(33 "B.Fab" user "Ref Des/Assembly Bottom")
	)
	(footprint ""
		(layer "F.Cu")
		(at 430.276 -154.94 -90)
		(property "Reference" "J8A1"
			(at 15.64767 10.287 0)
			(unlocked yes)
			(layer "B.SilkS")
			(effects
				(font
					(size 0.7874 0.5842)
					(thickness 0.1524)
				)
				(justify left mirror)
			)
		)
		(property "Value" ""
			(at 0 0 270)
			(layer "F.Fab")
			(effects
				(font
					(size 1.27 1.27)
				)
			)
		)
		(duplicate_pad_numbers_are_jumpers no)
		(pad "2D8" thru_hole circle
			(at 9.99998 17.249902 270)
			(size 0.7874 0.7874)
			(drill 0.381)
			(layers "*.Cu" "*.Mask")
			(remove_unused_layers no)
			(net "SATA6G_P6_TX_C_DN")
			(clearance 0.1143)
			(thermal_gap 0.1143)
		)
		(pad "2D9" thru_hole circle
			(at 10.700004 17.999964 270)
			(size 0.7874 0.7874)
			(drill 0.381)
			(layers "*.Cu" "*.Mask")
			(remove_unused_layers no)
			(net "GND")
			(clearance 0.1143)
			(thermal_gap 0.1143)
		)
	)
)
